G04 ================== begin FILE IDENTIFICATION RECORD ==================*
G04 Layout Name:  13130-1b.brd*
G04 Film Name:    DIF_REF_TOP*
G04 File Format:  Gerber RS274X*
G04 File Origin:  Cadence Allegro 16.5-S037*
G04 Origin Date:  Thu Nov 13 18:47:02 2014*
G04 *
G04 Layer:  BOARD GEOMETRY/OUTLINE*
G04 Layer:  BOARD GEOMETRY/DIF_REF_TOP*
G04 Layer:  BOARD GEOMETRY/PANEL_OUTLINE*
G04 *
G04 Offset:    (0.00 0.00)*
G04 Mirror:    No*
G04 Mode:      Positive*
G04 Rotation:  0*
G04 FullContactRelief:  No*
G04 UndefLineWidth:     6.00*
G04 ================== end FILE IDENTIFICATION RECORD ====================*
%FSLAX35Y35*MOIN*%
%IR0*IPPOS*OFA0.00000B0.00000*MIA0B0*SFA1.00000B1.00000*%
%ADD10C,.004*%
%ADD11C,.005*%
%ADD12C,.006*%
%ADD13C,.007*%
%ADD14C,.0055*%
%ADD15C,.0085*%
G75*
%LPD*%
G75*
G54D10*
G01X309192Y118791D02*
X310512Y120111D01*
G01X309192Y117702D02*
Y118791D01*
G01X309194Y117700D02*
X309192Y117702D01*
G01X306994Y117725D02*
X310180Y120911D01*
G01X304402Y190950D02*
X315175D01*
G01X303480Y190028D02*
X304402Y190950D01*
G01X303480Y189100D02*
Y190028D01*
G01X304070Y191750D02*
X314180D01*
G01X301300Y188980D02*
X304070Y191750D01*
G01X301300Y188700D02*
Y188980D01*
G01X309700Y187997D02*
X311236Y186461D01*
G01X309844Y185656D02*
X312404D01*
G01X307500Y188000D02*
X309844Y185656D01*
G01X315840Y120111D02*
X319112Y121101D01*
G01X310512Y120111D02*
X315840D01*
G01X314942Y120911D02*
X315342Y121311D01*
G01X321992Y115189D02*
Y116451D01*
G01X320992Y114189D02*
X321992Y115189D01*
G01X320992Y112180D02*
Y114189D01*
G01X319640Y113300D02*
X319096D01*
G01X320192Y113852D02*
X319640Y113300D01*
G01X320192Y114521D02*
Y113852D01*
G01X320585Y114914D02*
X320192Y114521D01*
G01X320585Y115406D02*
Y114914D01*
G01X320200Y115791D02*
X320585Y115406D01*
G01X319282Y115791D02*
X320200D01*
G01X310180Y120911D02*
X314942D01*
G01X318332Y196071D02*
X318702Y196441D01*
G01X318332Y193633D02*
Y196071D01*
G01X317630Y192931D02*
X318332Y193633D01*
G01X317156Y192931D02*
X317630D01*
G01X315175Y190950D02*
X317156Y192931D01*
G01X317132Y194039D02*
Y194131D01*
G01X314843Y191750D02*
X317132Y194039D01*
G01X314513Y191750D02*
X314843D01*
G01X314512Y191751D02*
X314513Y191750D01*
G01X314181Y191751D02*
X314512D01*
G01X314180Y191750D02*
X314181Y191751D01*
G01X319011Y189381D02*
X320112D01*
G01X317611Y190781D02*
X319011Y189381D01*
G01X316614Y190781D02*
X317611D01*
G01X315912Y190079D02*
X316614Y190781D01*
G01X315912Y190001D02*
Y190079D01*
G01X312372Y186461D02*
X315912Y190001D01*
G01X311236Y186461D02*
X312372D01*
G01X316624Y189581D02*
X317112D01*
G01X312704Y185661D02*
X316624Y189581D01*
G01X312409Y185661D02*
X312704D01*
G01X312404Y185656D02*
X312409Y185661D01*
G01X338512Y205368D02*
Y204751D01*
G01X336932Y206948D02*
X338512Y205368D01*
G01X336932Y207400D02*
Y206948D01*
G01X336000Y208332D02*
X336932Y207400D01*
G01X336000Y210800D02*
Y208332D01*
G01X333404Y213400D02*
X336000Y210800D01*
G01X331658Y212660D02*
X332398Y213400D01*
G01X336800Y211132D02*
X333736Y214200D01*
G01X336800Y208664D02*
Y211132D01*
G01X337732Y207732D02*
X336800Y208664D01*
G01X337732Y207280D02*
Y207732D01*
G01X339712Y205300D02*
X337732Y207280D01*
G01X339712Y204253D02*
Y205300D01*
G01X338822Y200601D02*
X339712Y204253D01*
G01X344202Y208934D02*
X339500Y213636D01*
G01X339512Y210000D02*
X338967Y209455D01*
G01X340600Y210000D02*
X339512D01*
G01X342602Y207998D02*
X340600Y210000D01*
G01X340502Y203760D02*
X342592Y205850D01*
G01X340502Y202300D02*
Y203760D01*
G01X341502Y199771D02*
X340502Y202300D01*
G01X340932Y210800D02*
X343402Y208330D01*
G01X339800Y210800D02*
X340932D01*
G01X338926Y211674D02*
X339800Y210800D01*
G01X332398Y213400D02*
X333404D01*
G01X332276Y214200D02*
X331616Y214860D01*
G01X333736Y214200D02*
X332276D01*
G01X337990Y216380D02*
X337341Y215731D01*
G01X338898Y216380D02*
X337990D01*
G01X339500Y215778D02*
X338898Y216380D01*
G01X339500Y213636D02*
Y215778D01*
G01X340300Y213968D02*
X345002Y209266D01*
G01X340300Y216110D02*
Y213968D01*
G01X339230Y217180D02*
X340300Y216110D01*
G01X338088Y217180D02*
X339230D01*
G01X337307Y217961D02*
X338088Y217180D01*
G01X344202Y206766D02*
Y208934D01*
G01X344742Y206226D02*
X344202Y206766D01*
G01X344742Y204941D02*
Y206226D01*
G01X344342Y204541D02*
X344742Y204941D01*
G01X345542Y204043D02*
X344132Y200771D01*
G01X345542Y206558D02*
Y204043D01*
G01X345002Y207098D02*
X345542Y206558D01*
G01X345002Y209266D02*
Y207098D01*
G01X342602Y205937D02*
Y207998D01*
G01X342592Y205927D02*
X342602Y205937D01*
G01X342592Y205850D02*
Y205927D01*
G01X341702Y203828D02*
Y202771D01*
G01X343402Y205528D02*
X341702Y203828D01*
G01X343402Y208330D02*
Y205528D01*
G01X348302Y207631D02*
X347162Y206491D01*
G01X348302Y209538D02*
Y207631D01*
G01X347593Y210247D02*
X348302Y209538D01*
G01X347593Y210277D02*
Y210247D01*
G01X347315Y204684D02*
X346252Y202531D01*
G01X349102Y206471D02*
X347315Y204684D01*
G01X349102Y211038D02*
Y206471D01*
G01X347664Y212476D02*
X349102Y211038D01*
G01X349942Y213058D02*
X348550Y214450D01*
G01X349942Y206179D02*
Y213058D01*
G01X348542Y204779D02*
X349942Y206179D01*
G01X348542Y204091D02*
Y204779D01*
G01X349978Y203829D02*
X348662Y201181D01*
G01X349978Y205083D02*
Y203829D01*
G01X350742Y205847D02*
X349978Y205083D01*
G01X350742Y213390D02*
Y205847D01*
G01X353341Y210960D02*
X353594Y210707D01*
G01X352689Y210960D02*
X353341D01*
G01X352342Y210613D02*
X352689Y210960D01*
G01X352342Y205183D02*
Y210613D01*
G01X352182Y205023D02*
X352342Y205183D01*
G01X352182Y204101D02*
Y205023D01*
G01X350982Y203700D02*
X352162Y201181D01*
G01X350982Y204955D02*
Y203700D01*
G01X351542Y205515D02*
X350982Y204955D01*
G01X351542Y211055D02*
Y205515D01*
G01X353385Y212898D02*
X351542Y211055D01*
G01X356100Y206591D02*
X357442Y205249D01*
G01X356100Y213600D02*
Y206591D01*
G01X356242Y205317D02*
Y204751D01*
G01X355300Y206259D02*
X356242Y205317D01*
G01X355300Y213932D02*
Y206259D01*
G01X344002Y214450D02*
X343242Y213690D01*
G01X348550Y214450D02*
X344002D01*
G01X348882Y215250D02*
X350742Y213390D01*
G01X343858Y215250D02*
X348882D01*
G01X343198Y215910D02*
X343858Y215250D01*
G01X358841Y216341D02*
X356100Y213600D01*
G01X357966Y216598D02*
X355300Y213932D01*
G01X368282Y104832D02*
X370602Y107152D01*
G01X368282Y103020D02*
Y104832D01*
G01X366158Y100896D02*
X368282Y103020D01*
G01X364060Y100896D02*
X366158D01*
G01X362134Y98970D02*
X364060Y100896D01*
G01X362134Y98434D02*
Y98970D01*
G01X361200Y97500D02*
X362134Y98434D01*
G01X370403Y104900D02*
X370732Y104571D01*
G01X369482Y104900D02*
X370403D01*
G01X369082Y104500D02*
X369482Y104900D01*
G01X369082Y102688D02*
Y104500D01*
G01X366490Y100096D02*
X369082Y102688D01*
G01X364392Y100096D02*
X366490D01*
G01X362934Y98638D02*
X364392Y100096D01*
G01X362934Y91934D02*
Y98638D01*
G01X361200Y90200D02*
X362934Y91934D01*
G01X370602Y107152D02*
Y107481D01*
G01X365182Y201945D02*
X364022Y197931D01*
G01X357442Y204253D02*
X356552Y200601D01*
G01X357442Y205249D02*
Y204253D01*
G01X362347Y213100D02*
Y221879D01*
G01X361200Y211953D02*
X362347Y213100D01*
G01X361200Y207132D02*
Y211953D01*
G01X360862Y206794D02*
X361200Y207132D01*
G01X360862Y204043D02*
Y206794D01*
G01X361862Y200771D02*
X360862Y204043D01*
G01X363147Y212768D02*
Y221547D01*
G01X362000Y211621D02*
X363147Y212768D01*
G01X362000Y206800D02*
Y211621D01*
G01X361662Y206462D02*
X362000Y206800D01*
G01X361662Y204941D02*
Y206462D01*
G01X362062Y204541D02*
X361662Y204941D01*
G01X364200Y202749D02*
X363982Y202531D01*
G01X364200Y204320D02*
Y202749D01*
G01X362800Y205720D02*
X364200Y204320D01*
G01X362800Y210036D02*
Y205720D01*
G01X364650Y211886D02*
X362800Y210036D01*
G01X364650Y220882D02*
Y211886D01*
G01X365182Y203029D02*
Y201945D01*
G01X365000Y203211D02*
X365182Y203029D01*
G01X365000Y204652D02*
Y203211D01*
G01X363600Y206052D02*
X365000Y204652D01*
G01X363600Y209704D02*
Y206052D01*
G01X365450Y211554D02*
X363600Y209704D01*
G01X365450Y220550D02*
Y211554D01*
G01X367750Y203900D02*
Y219950D01*
G01X366392Y201181D02*
X367750Y203900D01*
G01X366950Y204779D02*
Y220282D01*
G01X366262Y204091D02*
X366950Y204779D01*
G01X357700Y209422D02*
X358498Y210220D01*
G01X357700Y207332D02*
Y209422D01*
G01X358541Y206491D02*
X357700Y207332D01*
G01X359222Y206491D02*
X358541D01*
G01X358100Y205800D02*
X359422Y202771D01*
G01X356900Y207000D02*
X358100Y205800D01*
G01X356900Y210945D02*
Y207000D01*
G01X358382Y212427D02*
X356900Y210945D01*
G01X359827Y216341D02*
X358841D01*
G01X357966Y217516D02*
Y216598D01*
G01X364575Y224107D02*
Y229015D01*
G01X362347Y221879D02*
X364575Y224107D01*
G01X365375Y223775D02*
Y229015D01*
G01X363147Y221547D02*
X365375Y223775D01*
G01X376800Y233032D02*
X364650Y220882D01*
G01X377600Y232700D02*
X365450Y220550D01*
G01X367750Y219950D02*
X373300Y225500D01*
G01X366950Y220282D02*
X372968Y226300D01*
G01X364300Y229290D02*
Y229390D01*
G01X364575Y229015D02*
X364300Y229290D01*
G01X365650D02*
Y229390D01*
G01X365375Y229015D02*
X365650Y229290D01*
G01X381250Y85052D02*
Y97067D01*
G01X379500Y83302D02*
X381250Y85052D01*
G01X386012Y105059D02*
X384832Y106239D01*
G01X386012Y104000D02*
Y105059D01*
G01X385612Y103600D02*
X386012Y104000D01*
G01X385612Y101429D02*
Y103600D01*
G01X381250Y97067D02*
X385612Y101429D01*
G01X379500Y90650D02*
Y90600D01*
G01X380450Y91600D02*
X379500Y90650D01*
G01X380450Y97399D02*
Y91600D01*
G01X384812Y101761D02*
X380450Y97399D01*
G01X384812Y104561D02*
Y101761D01*
G01X387032Y120839D02*
X385721Y119528D01*
G01X387032Y121101D02*
Y120839D01*
G01X384832Y106239D02*
Y107481D01*
G01X385523Y122592D02*
Y122532D01*
G01X387032Y124101D02*
X385523Y122592D01*
G01X385339Y187561D02*
X386092D01*
G01X384708Y188192D02*
X385339Y187561D01*
G01X384708Y188910D02*
Y188192D01*
G01X386062Y184561D02*
X386092D01*
G01X384600Y186023D02*
X386062Y184561D01*
G01X384600Y186100D02*
Y186023D01*
G01X377334Y206873D02*
X376952Y206491D01*
G01X377334Y209966D02*
Y206873D01*
G01X376300Y211000D02*
X377334Y209966D01*
G01X377152Y204906D02*
Y202771D01*
G01X378134Y205888D02*
X377152Y204906D01*
G01X378134Y210298D02*
Y205888D01*
G01X377900Y210532D02*
X378134Y210298D01*
G01X377900Y214600D02*
Y210532D01*
G01X376160Y226540D02*
X376196Y226576D01*
G01X375772Y226540D02*
X376160D01*
G01X374732Y225500D02*
X375772Y226540D01*
G01X373300Y225500D02*
X374732D01*
G01X375241Y227141D02*
Y227531D01*
G01X374400Y226300D02*
X375241Y227141D01*
G01X372968Y226300D02*
X374400D01*
G01X376300Y216200D02*
X377900Y214600D01*
G01X376800Y233700D02*
Y233032D01*
G01X376525Y233975D02*
X376800Y233700D01*
G01X376525Y234075D02*
Y233975D01*
G01X377600Y233750D02*
Y232700D01*
G01X377875Y234025D02*
X377600Y233750D01*
G01X377875Y234075D02*
Y234025D01*
G01X397300Y89168D02*
X398800Y90668D01*
G01X401162Y102169D02*
Y102171D01*
G01X400628Y101635D02*
X401162Y102169D01*
G01X400628Y101032D02*
Y101635D01*
G01X398800Y99204D02*
X400628Y101032D01*
G01X398800Y90668D02*
Y99204D01*
G01X399828Y101364D02*
Y105787D01*
G01X398000Y99536D02*
X399828Y101364D01*
G01X398000Y97500D02*
Y99536D01*
G01X397100Y96600D02*
X398000Y97500D01*
G01X399828Y105787D02*
X400152Y106111D01*
G01X402239Y181561D02*
X401732D01*
G01X403600Y180200D02*
X402239Y181561D01*
G01X403022Y191851D02*
X401732Y190561D01*
G01X402967Y194796D02*
X401732Y193561D01*
G01X403600Y182693D02*
X401732Y184561D01*
G01X391292Y205151D02*
X391692Y204751D01*
G01X391292Y208440D02*
Y205151D01*
G01X390900Y208832D02*
X391292Y208440D01*
G01X390900Y212500D02*
Y208832D01*
G01X392100Y213700D02*
X390900Y212500D01*
G01X392002Y202657D02*
Y200601D01*
G01X390492Y204167D02*
X392002Y202657D01*
G01X390492Y208108D02*
Y204167D01*
G01X390100Y208500D02*
X390492Y208108D01*
G01X390100Y218950D02*
Y208500D01*
G01X391950Y220800D02*
X390100Y218950D01*
G01X415411Y103911D02*
X416212D01*
G01X415122Y103622D02*
X415411Y103911D01*
G01X415122Y102800D02*
Y103622D01*
G01X415550Y102372D02*
X415122Y102800D01*
G01X415550Y99466D02*
Y102372D01*
G01X416300Y98716D02*
X415550Y99466D01*
G01X416300Y91828D02*
Y98716D01*
G01X414722Y90250D02*
X416300Y91828D01*
G01X414750Y98128D02*
X414622Y98000D01*
G01X414750Y102040D02*
Y98128D01*
G01X414322Y102468D02*
X414750Y102040D01*
G01X414322Y103800D02*
Y102468D01*
G01X415902Y108061D02*
X414322Y103800D01*
G01X403600Y182400D02*
Y182693D01*
G01X406792Y184192D02*
Y183061D01*
G01X407224Y184624D02*
X406792Y184192D01*
G01X408242Y184624D02*
X407224D01*
G01X405707Y184976D02*
X406792Y186061D01*
G01X405231Y184976D02*
X405707D01*
G01X406792Y191908D02*
Y192061D01*
G01X408200Y190500D02*
X406792Y191908D01*
G01Y194108D02*
Y195061D01*
G01X407300Y193600D02*
X406792Y194108D01*
G01X408100Y193600D02*
X407300D01*
G01X403022Y192094D02*
Y191851D01*
G01X402967Y195005D02*
Y194796D01*
G01X417990Y211682D02*
X420208Y213900D01*
G01X419172Y208192D02*
X417990Y209374D01*
G01X417172Y203860D02*
X419172Y205860D01*
G01X417172Y202531D02*
Y203860D01*
G01X408096Y202895D02*
X407752Y202551D01*
G01X408096Y209896D02*
Y202895D01*
G01X410500Y212300D02*
X408096Y209896D01*
G01X410500Y223550D02*
Y212300D01*
G01X408896Y205277D02*
X409422Y204751D01*
G01X408896Y209564D02*
Y205277D01*
G01X411300Y211968D02*
X408896Y209564D01*
G01X411300Y217600D02*
Y211968D01*
G01X412050Y225100D02*
X410500Y223550D01*
G01X412100Y218400D02*
X411300Y217600D01*
G01X408450Y232850D02*
X408350D01*
G01X408725Y232575D02*
X408450Y232850D01*
G01X415357Y232575D02*
X408725D01*
G01X424050Y223882D02*
X415357Y232575D01*
G01X408450Y231500D02*
X408350D01*
G01X408725Y231775D02*
X408450Y231500D01*
G01X415025Y231775D02*
X408725D01*
G01X423250Y223550D02*
X415025Y231775D01*
G01X427560Y104770D02*
Y105640D01*
G01X420600Y118700D02*
Y118300D01*
G01X420100Y119200D02*
X420600Y118700D01*
G01X419100Y119200D02*
X420100D01*
G01X418312Y118412D02*
X419100Y119200D01*
G01X418312Y118101D02*
Y118412D01*
G01X418812Y120600D02*
X418312Y121100D01*
G01X420672Y120600D02*
X418812D01*
G01X423372Y116554D02*
X422042Y115224D01*
G01X423372Y116601D02*
Y116554D01*
G01Y113654D02*
Y113601D01*
G01X424700Y114982D02*
X423372Y113654D01*
G01X424700Y115000D02*
Y114982D01*
G01X426831Y114300D02*
X426132Y113601D01*
G01X427900Y114300D02*
X426831D01*
G01X426233Y116500D02*
X426132Y116601D01*
G01X428100Y116500D02*
X426233D01*
G01X427069Y106131D02*
X426192D01*
G01X427560Y105640D02*
X427069Y106131D01*
G01X428282Y107148D02*
Y108061D01*
G01X428294Y107148D02*
X428282D01*
G01X429105Y106337D02*
X428294Y107148D01*
G01X418312Y121100D02*
Y121101D01*
G01X422545Y132721D02*
X422402D01*
G01X423666Y131600D02*
X422545Y132721D01*
G01X423800Y131600D02*
X423666D01*
G01X423900Y131500D02*
X423800Y131600D01*
G01X419545Y132721D02*
X420942Y131324D01*
G01X419402Y132721D02*
X419545D01*
G01X420728Y149687D02*
X420861D01*
G01X419402Y148361D02*
X420728Y149687D01*
G01X422299Y148361D02*
X420861Y146923D01*
G01X422402Y148361D02*
X422299D01*
G01X430694Y141333D02*
Y142275D01*
G01X429902Y140541D02*
X430694Y141333D01*
G01X429668Y137781D02*
X428390Y139059D01*
G01X429902Y137781D02*
X429668D01*
G01X420984Y162659D02*
X422402Y161241D01*
G01X420804Y162659D02*
X420984D01*
G01X420359Y161241D02*
X419402D01*
G01X420900Y160700D02*
X420359Y161241D01*
G01X420900Y160037D02*
Y160700D01*
G01X419402Y177302D02*
Y176881D01*
G01X420217Y178117D02*
X419402Y177302D01*
G01X420922Y178117D02*
X420217D01*
G01X423795Y178274D02*
X423842D01*
G01X422402Y176881D02*
X423795Y178274D01*
G01X428460Y170293D02*
X428431Y170264D01*
G01X428460Y170379D02*
Y170293D01*
G01X429902Y171821D02*
X428460Y170379D01*
G01X429590Y169061D02*
X429902D01*
G01X428238Y167709D02*
X429590Y169061D01*
G01X422200Y213100D02*
X424050Y214950D01*
G01X420540Y213100D02*
X422200D01*
G01X418790Y211350D02*
X420540Y213100D01*
G01X418790Y209706D02*
Y211350D01*
G01X419972Y208524D02*
X418790Y209706D01*
G01X419972Y205528D02*
Y208524D01*
G01X419452Y205008D02*
X419972Y205528D01*
G01X419452Y204091D02*
Y205008D01*
G01X417990Y209374D02*
Y211682D01*
G01X419172Y205860D02*
Y208192D01*
G01X424050Y214950D02*
Y223882D01*
G01X423250Y215282D02*
Y223550D01*
G01X421868Y213900D02*
X423250Y215282D01*
G01X420208Y213900D02*
X421868D01*
G01X441553Y136102D02*
X441332Y136323D01*
G01X443361Y136102D02*
X441553D01*
G01X451663Y127800D02*
X443361Y136102D01*
G01X441221Y135302D02*
X439712Y136811D01*
G01X443029Y135302D02*
X441221D01*
G01X451331Y127000D02*
X443029Y135302D01*
G01X441332Y136323D02*
Y137011D01*
G01X439712Y136811D02*
X437612D01*
G01X450231Y175700D02*
X441332Y166801D01*
G01X437247Y181806D02*
X436022Y183031D01*
G01X441706Y181806D02*
X437247D01*
G01X443432Y183532D02*
X441706Y181806D01*
G01X441830Y168431D02*
X449899Y176500D01*
G01X439400Y168431D02*
X441830D01*
G01X438369Y167400D02*
X439400Y168431D01*
G01X437683Y167400D02*
X438369D01*
G01X437372Y167711D02*
X437683Y167400D01*
G01X439477Y182606D02*
X438932Y183151D01*
G01X441374Y182606D02*
X439477D01*
G01X442632Y183864D02*
X441374Y182606D01*
G01X442632Y185146D02*
Y183864D01*
G01X452586Y195100D02*
X442632Y185146D01*
G01X443432Y184814D02*
Y183532D01*
G01X451918Y193300D02*
X443432Y184814D01*
G01X461600Y127800D02*
X451663D01*
G01X463200Y126200D02*
X461600Y127800D01*
G01X455600Y127000D02*
X451331D01*
G01X456500Y126100D02*
X455600Y127000D01*
G01X458400Y176500D02*
X460000Y174900D01*
G01X449899Y176500D02*
X458400D01*
G01X452200Y175700D02*
X450231D01*
G01X453000Y174900D02*
X452200Y175700D01*
G01X458600Y195100D02*
X452586D01*
G01X460400Y193300D02*
X458600Y195100D01*
G01X453400Y193300D02*
X451918D01*
G54D11*
G01X84200Y212900D02*
Y216513D01*
G01X87450Y209650D02*
X84200Y212900D01*
G01X89950Y209650D02*
X87450D01*
G01X90400Y209200D02*
X89950Y209650D01*
G01X90400Y208500D02*
Y209200D01*
G01X89000Y207100D02*
X90400Y208500D01*
G01X89700Y206400D02*
X89000Y207100D01*
G01X89700Y204200D02*
Y206400D01*
G01X89500Y204000D02*
X89700Y204200D01*
G01X89800Y203700D02*
X89500Y204000D01*
G01X89800Y200800D02*
Y203700D01*
G01X89600Y200600D02*
X89800Y200800D01*
G01X91700Y201500D02*
X92600Y200600D01*
G01X91700Y202807D02*
Y201500D01*
G01X92800Y203907D02*
X91700Y202807D01*
G01X92800Y203908D02*
Y203907D01*
G01X92900Y204008D02*
X92800Y203908D01*
G01X85200Y213315D02*
Y216413D01*
G01X87865Y210650D02*
X85200Y213315D01*
G01X90365Y210650D02*
X87865D01*
G01X91400Y209615D02*
X90365Y210650D01*
G01X91400Y208500D02*
Y209615D01*
G01X92700Y207200D02*
X91400Y208500D01*
G01X92600Y207100D02*
X92700Y207200D01*
G01X92100Y204808D02*
X92900Y204008D01*
G01X92100Y206600D02*
Y204808D01*
G01X92600Y207100D02*
X92100Y206600D01*
G01X83713Y217000D02*
Y218689D01*
G01X84200Y216513D02*
X83713Y217000D01*
G01X85287Y216500D02*
Y218689D01*
G01X85200Y216413D02*
X85287Y216500D01*
G01X322200Y210400D02*
X321600Y211000D01*
G01X328673Y210400D02*
X322200D01*
G01X322400Y209500D02*
X321600Y208700D01*
G01X328300Y209500D02*
X322400D01*
G01X317800Y213700D02*
X317200Y213100D01*
G01X323256Y213310D02*
X322866Y213700D01*
G01X324756Y213310D02*
X323256D01*
G01X325146Y213700D02*
X324756Y213310D01*
G01X317900Y214600D02*
X317200Y215300D01*
G01X327019Y214600D02*
X317900D01*
G01X322866Y213700D02*
X317800D01*
G01X326646D02*
X325146D01*
G01X331621Y207452D02*
X328673Y210400D01*
G01X331621Y205395D02*
Y207452D01*
G01X330812Y204586D02*
X331621Y205395D01*
G01X330812Y204091D02*
Y204586D01*
G01X330721Y207079D02*
X328300Y209500D01*
G01X330721Y205768D02*
Y207079D01*
G01X329562Y204609D02*
X330721Y205768D01*
G01X329562Y203700D02*
Y204609D01*
G01X330932Y201181D02*
X329562Y203700D01*
G01X333596Y208023D02*
X327019Y214600D01*
G01X333596Y204967D02*
Y208023D01*
G01X334462Y204101D02*
X333596Y204967D01*
G01X332696Y207650D02*
X326646Y213700D01*
G01X332696Y204100D02*
Y207650D01*
G01X334432Y201181D02*
X332696Y204100D01*
G01X408615Y237500D02*
X401838Y244277D01*
G01X400861Y243839D02*
X399438D01*
G01X408200Y236500D02*
X400861Y243839D01*
G01X401838Y244277D02*
Y246248D01*
G01X442915Y237500D02*
X408615D01*
G01X442500Y236500D02*
X408200D01*
G01X448604Y147811D02*
X453900D01*
G01X444415Y152000D02*
X448604Y147811D01*
G01X448189Y146811D02*
X450800D01*
G01X444000Y151000D02*
X448189Y146811D01*
G01X440849Y151000D02*
X444000D01*
G01X440500Y150651D02*
X440849Y151000D01*
G01X438042Y150651D02*
X440500D01*
G01X437372Y149981D02*
X438042Y150651D01*
G01X439481Y152000D02*
X444415D01*
G01X439382Y151901D02*
X439481Y152000D01*
G01X456550Y223865D02*
X442915Y237500D01*
G01X455550Y223450D02*
X442500Y236500D01*
G01X462200Y143563D02*
X465300D01*
G01X462200Y147063D02*
X465200D01*
G01X456211Y145500D02*
X453900Y147811D01*
G01X457237Y145500D02*
X456211D01*
G01X458800Y147063D02*
X457237Y145500D01*
G01X453900Y149150D02*
Y147811D01*
G01X453485Y146811D02*
X450800D01*
G01X455796Y144500D02*
X453485Y146811D01*
G01X457863Y144500D02*
X455796D01*
G01X458800Y143563D02*
X457863Y144500D01*
G01X450800Y145400D02*
Y146811D01*
G01X456550Y211899D02*
Y223865D01*
G01X477550Y190899D02*
X456550Y211899D01*
G01X455550Y211484D02*
Y223450D01*
G01X476550Y190484D02*
X455550Y211484D01*
G01X465300Y143563D02*
X465500Y143763D01*
G01X466500Y144763D02*
X484763D01*
G01X465500Y143763D02*
X466500Y144763D01*
G01X465200Y147063D02*
X465500Y146763D01*
G01X466500Y145763D02*
X484348D01*
G01X465500Y146763D02*
X466500Y145763D01*
G01X477550Y170865D02*
Y190899D01*
G01X491000Y157415D02*
X477550Y170865D01*
G01X476550Y170450D02*
Y190484D01*
G01X490000Y157000D02*
X476550Y170450D01*
G01X491000Y151000D02*
Y157415D01*
G01X484763Y144763D02*
X491000Y151000D01*
G01X490000Y151415D02*
Y157000D01*
G01X484348Y145763D02*
X490000Y151415D01*
G54D12*
G01X-31497Y-1D02*
X26377D01*
G01X-35434Y3936D02*
G03X-31497Y-1I3937J0D01*
G01X-35434Y585039D02*
Y3936D01*
G01X-7874Y588976D02*
X-31497D01*
G01D02*
G03X-35434Y585039I0J-3937D01*
G01X-12698Y15747D02*
G03I-6988J0D01*
G01Y573227D02*
G03I-6988J0D01*
G01X822835Y290551D02*
X3937D01*
G03X0Y286614I0J-3937D01*
G01Y61811D01*
G03X3937Y57874I3937J0D01*
G01X53937D01*
G02X57874Y53937I0J-3937D01*
G01Y16142D01*
X338189D01*
Y39961D01*
G02X345669I3740J0D01*
G01Y16142D01*
X389764D01*
Y42126D01*
G02X393701Y46063I3937J0D01*
G01X409449D01*
G02X413386Y42126I0J-3937D01*
G01Y3937D01*
G03X417323Y0I3937J0D01*
G01X822835D01*
G03X826772Y3937I0J3937D01*
G01Y286614D01*
G03X822835Y290551I-3937J0D01*
G01X826773Y286614D02*
G03X822836Y290551I-3937J0D01*
G01X3938D01*
G03X1Y286614I0J-3937D01*
G01Y61811D01*
G03X3938Y57874I3937J0D01*
G01X53938D01*
G02X57875Y53937I0J-3937D01*
G01Y12598D01*
X59844Y10629D01*
X336222D01*
X338190Y12598D01*
Y39960D01*
G02X345671I3740J0D01*
G01Y12598D01*
X347639Y10629D01*
X387797D01*
X389765Y12598D01*
Y42126D01*
G02X393702Y46063I3937J0D01*
G01X409450D01*
G02X413387Y42126I0J-3937D01*
G01Y3937D01*
G03X417324Y0I3937J0D01*
G01X822836D01*
G03X826773Y3937I0J3937D01*
G01Y286614D01*
G01D02*
G03X822836Y290551I-3937J0D01*
G01X3938D01*
G03X1Y286614I0J-3937D01*
G01Y61811D01*
G03X3938Y57874I3937J0D01*
G01X53938D01*
G02X57875Y53937I0J-3937D01*
G01Y12598D01*
X59844Y10629D01*
X336222D01*
X338190Y12598D01*
Y39960D01*
G02X345671I3740J0D01*
G01Y12598D01*
X347639Y10629D01*
X387797D01*
X389765Y12598D01*
Y42126D01*
G02X393702Y46063I3937J0D01*
G01X409450D01*
G02X413387Y42126I0J-3937D01*
G01Y3937D01*
G03X417324Y0I3937J0D01*
G01X822836D01*
G03X826773Y3937I0J3937D01*
G01Y286614D01*
G01X22440Y49999D02*
X-3937D01*
G01X-7874Y53936D02*
Y72440D01*
G01Y53936D02*
G03X-3937Y49999I3937J0D01*
G01X0Y72440D02*
G03X-7874I-3937J0D01*
G01Y103149D02*
G03X0I3937J0D01*
G01X-7874D02*
Y210235D01*
G01X0D02*
G03X-7874I-3937J0D01*
G01Y240944D02*
Y348031D01*
G01Y240944D02*
G03X0I3937J0D01*
G01X-3Y302361D02*
G03X3934Y298424I3937J0D01*
G01X822832D01*
G03X826769Y302361I0J3937D01*
G01Y527164D01*
G03X822832Y531101I-3937J0D01*
G01X772832D01*
G02X768895Y535038I0J3937D01*
G01Y576377D01*
X766926Y578346D01*
X490548D01*
X488580Y576377D01*
Y549015D01*
G02X481099I-3740J0D01*
G01Y576377D01*
X479131Y578346D01*
X438973D01*
X437005Y576377D01*
Y546849D01*
G02X433068Y542912I-3937J0D01*
G01X417320D01*
G02X413383Y546849I0J3937D01*
G01Y585038D01*
G03X409446Y588975I-3937J0D01*
G01X3934D01*
G03X-3Y585038I0J-3937D01*
G01Y302361D01*
G01X0Y348031D02*
G03X-7874I-3937J0D01*
G01Y378739D02*
Y485826D01*
G01Y378739D02*
G03X0I3937J0D01*
G01Y485826D02*
G03X-7874I-3937J0D01*
G01Y516535D02*
Y588976D01*
G01Y516535D02*
G03X0I3937J-1D01*
G01X17137Y687650D02*
Y675650D01*
G01X14837Y687650D02*
X19437D01*
G01X21437Y675650D02*
Y687650D01*
G01Y681850D02*
X21937Y682850D01*
X22437Y683450D01*
X23237Y683650D01*
X23837Y683450D01*
X24537Y682650D01*
X24837Y681450D01*
Y675650D01*
G01X29137Y683650D02*
Y675650D01*
G01Y686850D02*
X28937Y687050D01*
Y687450D01*
X29137Y687650D01*
X29337Y687450D01*
Y687050D01*
X29137Y686850D01*
G01X33637Y677050D02*
X34137Y676250D01*
X34837Y675650D01*
X35437D01*
X36037Y676050D01*
X36437Y676650D01*
X36637Y677450D01*
X36537Y678650D01*
X36137Y679250D01*
X34337Y680450D01*
X33937Y681850D01*
X34137Y682850D01*
X34537Y683450D01*
X35137Y683650D01*
X35737Y683450D01*
X36337Y682850D01*
G01X45737Y672650D02*
X46437Y671850D01*
X47237Y671650D01*
X47937Y671850D01*
X48537Y672850D01*
X48937Y674250D01*
Y683650D01*
G01Y682050D02*
X48537Y682850D01*
X47937Y683450D01*
X47237Y683650D01*
X46437Y683250D01*
X45937Y682450D01*
X45537Y681050D01*
X45337Y679650D01*
X45437Y678450D01*
X45837Y677050D01*
X46437Y676050D01*
X47237Y675650D01*
X47837Y675850D01*
X48537Y676650D01*
X48937Y677450D01*
G01X51637Y681050D02*
X54837D01*
X54537Y682450D01*
X54037Y683250D01*
X53337Y683650D01*
X52637Y683450D01*
X52037Y682850D01*
X51637Y681450D01*
X51437Y680250D01*
Y679050D01*
X51637Y677850D01*
X52137Y676650D01*
X52737Y675850D01*
X53437Y675650D01*
X54137Y676050D01*
X54837Y677250D01*
G01X57737Y675650D02*
Y683650D01*
G01Y682050D02*
X58237Y682850D01*
X58737Y683450D01*
X59437Y683650D01*
X59937Y683450D01*
X60537Y682850D01*
G01X63337Y675650D02*
Y687650D01*
G01Y681650D02*
X63837Y682850D01*
X64437Y683450D01*
X65037Y683650D01*
X65937Y683250D01*
X66537Y682450D01*
X66937Y681050D01*
Y679450D01*
X66737Y677850D01*
X66337Y676650D01*
X65637Y675850D01*
X65037Y675650D01*
X64437Y675850D01*
X63837Y676450D01*
X63337Y677450D01*
G01X69637Y681050D02*
X72837D01*
X72537Y682450D01*
X72037Y683250D01*
X71337Y683650D01*
X70637Y683450D01*
X70037Y682850D01*
X69637Y681450D01*
X69437Y680250D01*
Y679050D01*
X69637Y677850D01*
X70137Y676650D01*
X70737Y675850D01*
X71437Y675650D01*
X72137Y676050D01*
X72837Y677250D01*
G01X75737Y675650D02*
Y683650D01*
G01Y682050D02*
X76237Y682850D01*
X76737Y683450D01*
X77437Y683650D01*
X77937Y683450D01*
X78537Y682850D01*
G01X89137Y683650D02*
Y675650D01*
G01Y686850D02*
X88937Y687050D01*
Y687450D01*
X89137Y687650D01*
X89337Y687450D01*
Y687050D01*
X89137Y686850D01*
G01X93637Y677050D02*
X94137Y676250D01*
X94837Y675650D01*
X95437D01*
X96037Y676050D01*
X96437Y676650D01*
X96637Y677450D01*
X96537Y678650D01*
X96137Y679250D01*
X94337Y680450D01*
X93937Y681850D01*
X94137Y682850D01*
X94537Y683450D01*
X95137Y683650D01*
X95737Y683450D01*
X96337Y682850D01*
G01X105537Y672650D02*
X106237Y671850D01*
X106837Y671650D01*
X107637Y672050D01*
X108237Y673050D01*
X108537Y674850D01*
Y683650D01*
G01Y686850D02*
X108337Y687050D01*
Y687450D01*
X108537Y687650D01*
X108737Y687450D01*
Y687050D01*
X108537Y686850D01*
G01X111437Y683650D02*
Y678050D01*
X111837Y676650D01*
X112437Y675850D01*
X113137Y675650D01*
X113837Y675850D01*
X114437Y676650D01*
X114837Y678050D01*
G01Y675650D02*
Y683650D01*
G01X117637Y677050D02*
X118137Y676250D01*
X118837Y675650D01*
X119437D01*
X120037Y676050D01*
X120437Y676650D01*
X120637Y677450D01*
X120537Y678650D01*
X120137Y679250D01*
X118337Y680450D01*
X117937Y681850D01*
X118137Y682850D01*
X118537Y683450D01*
X119137Y683650D01*
X119737Y683450D01*
X120337Y682850D01*
G01X125137Y687650D02*
Y675650D01*
G01X123737Y683650D02*
X126537D01*
G01X136537Y675650D02*
Y685850D01*
X136737Y686850D01*
X137137Y687450D01*
X137737Y687650D01*
X138337Y687250D01*
X138637Y686250D01*
G01X137437Y682850D02*
X135437D01*
G01X143137Y675650D02*
X142537Y675850D01*
X141937Y676650D01*
X141537Y678050D01*
X141337Y679650D01*
X141537Y681250D01*
X141937Y682650D01*
X142537Y683450D01*
X143137Y683650D01*
X143737Y683450D01*
X144337Y682650D01*
X144737Y681250D01*
X144837Y679650D01*
X144737Y678050D01*
X144337Y676650D01*
X143737Y675850D01*
X143137Y675650D01*
G01X147737D02*
Y683650D01*
G01Y682050D02*
X148237Y682850D01*
X148737Y683450D01*
X149437Y683650D01*
X149937Y683450D01*
X150537Y682850D01*
G01X159037Y672050D02*
X159637Y671650D01*
X160437Y672050D01*
X160937Y672850D01*
X161337Y673850D01*
X161937Y677050D01*
X163237Y683650D01*
G01X160037D02*
X161937Y677050D01*
G01X167137Y675650D02*
X166537Y675850D01*
X165937Y676650D01*
X165537Y678050D01*
X165337Y679650D01*
X165537Y681250D01*
X165937Y682650D01*
X166537Y683450D01*
X167137Y683650D01*
X167737Y683450D01*
X168337Y682650D01*
X168737Y681250D01*
X168837Y679650D01*
X168737Y678050D01*
X168337Y676650D01*
X167737Y675850D01*
X167137Y675650D01*
G01X171437Y683650D02*
Y678050D01*
X171837Y676650D01*
X172437Y675850D01*
X173137Y675650D01*
X173837Y675850D01*
X174437Y676650D01*
X174837Y678050D01*
G01Y675650D02*
Y683650D01*
G01X183737Y675650D02*
Y683650D01*
G01Y682050D02*
X184237Y682850D01*
X184737Y683450D01*
X185437Y683650D01*
X185937Y683450D01*
X186537Y682850D01*
G01X189637Y681050D02*
X192837D01*
X192537Y682450D01*
X192037Y683250D01*
X191337Y683650D01*
X190637Y683450D01*
X190037Y682850D01*
X189637Y681450D01*
X189437Y680250D01*
Y679050D01*
X189637Y677850D01*
X190137Y676650D01*
X190737Y675850D01*
X191437Y675650D01*
X192137Y676050D01*
X192837Y677250D01*
G01X196537Y675650D02*
Y685850D01*
X196737Y686850D01*
X197137Y687450D01*
X197737Y687650D01*
X198337Y687250D01*
X198637Y686250D01*
G01X197437Y682850D02*
X195437D01*
G01X201637Y681050D02*
X204837D01*
X204537Y682450D01*
X204037Y683250D01*
X203337Y683650D01*
X202637Y683450D01*
X202037Y682850D01*
X201637Y681450D01*
X201437Y680250D01*
Y679050D01*
X201637Y677850D01*
X202137Y676650D01*
X202737Y675850D01*
X203437Y675650D01*
X204137Y676050D01*
X204837Y677250D01*
G01X207737Y675650D02*
Y683650D01*
G01Y682050D02*
X208237Y682850D01*
X208737Y683450D01*
X209437Y683650D01*
X209937Y683450D01*
X210537Y682850D01*
G01X213637Y681050D02*
X216837D01*
X216537Y682450D01*
X216037Y683250D01*
X215337Y683650D01*
X214637Y683450D01*
X214037Y682850D01*
X213637Y681450D01*
X213437Y680250D01*
Y679050D01*
X213637Y677850D01*
X214137Y676650D01*
X214737Y675850D01*
X215437Y675650D01*
X216137Y676050D01*
X216837Y677250D01*
G01X219437Y675650D02*
Y683650D01*
G01Y681650D02*
X219837Y682650D01*
X220437Y683450D01*
X221237Y683650D01*
X221937Y683450D01*
X222537Y682650D01*
X222837Y681250D01*
Y675650D01*
G01X228737Y682650D02*
X228037Y683450D01*
X227437Y683650D01*
X226637Y683250D01*
X226037Y682450D01*
X225637Y681050D01*
X225537Y679650D01*
X225637Y678250D01*
X226037Y677050D01*
X226637Y676050D01*
X227437Y675650D01*
X228137Y676050D01*
X228737Y676850D01*
G01X231637Y681050D02*
X234837D01*
X234537Y682450D01*
X234037Y683250D01*
X233337Y683650D01*
X232637Y683450D01*
X232037Y682850D01*
X231637Y681450D01*
X231437Y680250D01*
Y679050D01*
X231637Y677850D01*
X232137Y676650D01*
X232737Y675850D01*
X233437Y675650D01*
X234137Y676050D01*
X234837Y677250D01*
G01X245137Y687650D02*
Y675650D01*
G01X243737Y683650D02*
X246537D01*
G01X251137Y675650D02*
X250537Y675850D01*
X249937Y676650D01*
X249537Y678050D01*
X249337Y679650D01*
X249537Y681250D01*
X249937Y682650D01*
X250537Y683450D01*
X251137Y683650D01*
X251737Y683450D01*
X252337Y682650D01*
X252737Y681250D01*
X252837Y679650D01*
X252737Y678050D01*
X252337Y676650D01*
X251737Y675850D01*
X251137Y675650D01*
G01X262537D02*
Y685850D01*
X262737Y686850D01*
X263137Y687450D01*
X263737Y687650D01*
X264337Y687250D01*
X264637Y686250D01*
G01X263437Y682850D02*
X261437D01*
G01X269137Y683650D02*
Y675650D01*
G01Y686850D02*
X268937Y687050D01*
Y687450D01*
X269137Y687650D01*
X269337Y687450D01*
Y687050D01*
X269137Y686850D01*
G01X273437Y675650D02*
Y683650D01*
G01Y681650D02*
X273837Y682650D01*
X274437Y683450D01*
X275237Y683650D01*
X275937Y683450D01*
X276537Y682650D01*
X276837Y681250D01*
Y675650D01*
G01X282937Y687650D02*
Y675650D01*
G01Y677450D02*
X282537Y676450D01*
X281937Y675850D01*
X281237Y675650D01*
X280437Y676050D01*
X279837Y677050D01*
X279437Y678250D01*
X279337Y679650D01*
X279437Y681050D01*
X279837Y682250D01*
X280437Y683250D01*
X281237Y683650D01*
X281937Y683450D01*
X282437Y683050D01*
X282937Y682250D01*
G01X293137Y687650D02*
Y675650D01*
G01X291737Y683650D02*
X294537D01*
G01X297437Y675650D02*
Y687650D01*
G01Y681850D02*
X297937Y682850D01*
X298437Y683450D01*
X299237Y683650D01*
X299837Y683450D01*
X300537Y682650D01*
X300837Y681450D01*
Y675650D01*
G01X303637Y681050D02*
X306837D01*
X306537Y682450D01*
X306037Y683250D01*
X305337Y683650D01*
X304637Y683450D01*
X304037Y682850D01*
X303637Y681450D01*
X303437Y680250D01*
Y679050D01*
X303637Y677850D01*
X304137Y676650D01*
X304737Y675850D01*
X305437Y675650D01*
X306137Y676050D01*
X306837Y677250D01*
G01X318937Y687650D02*
Y675650D01*
G01Y677450D02*
X318537Y676450D01*
X317937Y675850D01*
X317237Y675650D01*
X316437Y676050D01*
X315837Y677050D01*
X315437Y678250D01*
X315337Y679650D01*
X315437Y681050D01*
X315837Y682250D01*
X316437Y683250D01*
X317237Y683650D01*
X317937Y683450D01*
X318437Y683050D01*
X318937Y682250D01*
G01X323137Y683650D02*
Y675650D01*
G01Y686850D02*
X322937Y687050D01*
Y687450D01*
X323137Y687650D01*
X323337Y687450D01*
Y687050D01*
X323137Y686850D01*
G01X328537Y675650D02*
Y685850D01*
X328737Y686850D01*
X329137Y687450D01*
X329737Y687650D01*
X330337Y687250D01*
X330637Y686250D01*
G01X329437Y682850D02*
X327437D01*
G01X334537Y675650D02*
Y685850D01*
X334737Y686850D01*
X335137Y687450D01*
X335737Y687650D01*
X336337Y687250D01*
X336637Y686250D01*
G01X335437Y682850D02*
X333437D01*
G01X339637Y681050D02*
X342837D01*
X342537Y682450D01*
X342037Y683250D01*
X341337Y683650D01*
X340637Y683450D01*
X340037Y682850D01*
X339637Y681450D01*
X339437Y680250D01*
Y679050D01*
X339637Y677850D01*
X340137Y676650D01*
X340737Y675850D01*
X341437Y675650D01*
X342137Y676050D01*
X342837Y677250D01*
G01X345737Y675650D02*
Y683650D01*
G01Y682050D02*
X346237Y682850D01*
X346737Y683450D01*
X347437Y683650D01*
X347937Y683450D01*
X348537Y682850D01*
G01X351637Y681050D02*
X354837D01*
X354537Y682450D01*
X354037Y683250D01*
X353337Y683650D01*
X352637Y683450D01*
X352037Y682850D01*
X351637Y681450D01*
X351437Y680250D01*
Y679050D01*
X351637Y677850D01*
X352137Y676650D01*
X352737Y675850D01*
X353437Y675650D01*
X354137Y676050D01*
X354837Y677250D01*
G01X357437Y675650D02*
Y683650D01*
G01Y681650D02*
X357837Y682650D01*
X358437Y683450D01*
X359237Y683650D01*
X359937Y683450D01*
X360537Y682650D01*
X360837Y681250D01*
Y675650D01*
G01X365137Y687650D02*
Y675650D01*
G01X363737Y683650D02*
X366537D01*
G01X371137D02*
Y675650D01*
G01Y686850D02*
X370937Y687050D01*
Y687450D01*
X371137Y687650D01*
X371337Y687450D01*
Y687050D01*
X371137Y686850D01*
G01X378937Y675650D02*
Y683650D01*
G01Y682250D02*
X378537Y683050D01*
X377937Y683450D01*
X377237Y683650D01*
X376537Y683250D01*
X375937Y682450D01*
X375537Y681250D01*
X375337Y679650D01*
X375537Y678050D01*
X375937Y676850D01*
X376537Y676050D01*
X377237Y675650D01*
X377937Y675850D01*
X378537Y676450D01*
X378937Y677250D01*
G01X383137Y675650D02*
Y687650D01*
G01X395137D02*
Y675650D01*
G01X393737Y683650D02*
X396537D01*
G01X399737Y675650D02*
Y683650D01*
G01Y682050D02*
X400237Y682850D01*
X400737Y683450D01*
X401437Y683650D01*
X401937Y683450D01*
X402537Y682850D01*
G01X408937Y675650D02*
Y683650D01*
G01Y682250D02*
X408537Y683050D01*
X407937Y683450D01*
X407237Y683650D01*
X406537Y683250D01*
X405937Y682450D01*
X405537Y681250D01*
X405337Y679650D01*
X405537Y678050D01*
X405937Y676850D01*
X406537Y676050D01*
X407237Y675650D01*
X407937Y675850D01*
X408537Y676450D01*
X408937Y677250D01*
G01X414737Y682650D02*
X414037Y683450D01*
X413437Y683650D01*
X412637Y683250D01*
X412037Y682450D01*
X411637Y681050D01*
X411537Y679650D01*
X411637Y678250D01*
X412037Y677050D01*
X412637Y676050D01*
X413437Y675650D01*
X414137Y676050D01*
X414737Y676850D01*
G01X417637Y681050D02*
X420837D01*
X420537Y682450D01*
X420037Y683250D01*
X419337Y683650D01*
X418637Y683450D01*
X418037Y682850D01*
X417637Y681450D01*
X417437Y680250D01*
Y679050D01*
X417637Y677850D01*
X418137Y676650D01*
X418737Y675850D01*
X419437Y675650D01*
X420137Y676050D01*
X420837Y677250D01*
G01X423637Y677050D02*
X424137Y676250D01*
X424837Y675650D01*
X425437D01*
X426037Y676050D01*
X426437Y676650D01*
X426637Y677450D01*
X426537Y678650D01*
X426137Y679250D01*
X424337Y680450D01*
X423937Y681850D01*
X424137Y682850D01*
X424537Y683450D01*
X425137Y683650D01*
X425737Y683450D01*
X426337Y682850D01*
G01X437137Y683650D02*
Y675650D01*
G01Y686850D02*
X436937Y687050D01*
Y687450D01*
X437137Y687650D01*
X437337Y687450D01*
Y687050D01*
X437137Y686850D01*
G01X441437Y675650D02*
Y683650D01*
G01Y681650D02*
X441837Y682650D01*
X442437Y683450D01*
X443237Y683650D01*
X443937Y683450D01*
X444537Y682650D01*
X444837Y681250D01*
Y675650D01*
G01X455137D02*
Y687650D01*
G01X462937Y675650D02*
Y683650D01*
G01Y682250D02*
X462537Y683050D01*
X461937Y683450D01*
X461237Y683650D01*
X460537Y683250D01*
X459937Y682450D01*
X459537Y681250D01*
X459337Y679650D01*
X459537Y678050D01*
X459937Y676850D01*
X460537Y676050D01*
X461237Y675650D01*
X461937Y675850D01*
X462537Y676450D01*
X462937Y677250D01*
G01X465037Y672050D02*
X465637Y671650D01*
X466437Y672050D01*
X466937Y672850D01*
X467337Y673850D01*
X467937Y677050D01*
X469237Y683650D01*
G01X466037D02*
X467937Y677050D01*
G01X471637Y681050D02*
X474837D01*
X474537Y682450D01*
X474037Y683250D01*
X473337Y683650D01*
X472637Y683450D01*
X472037Y682850D01*
X471637Y681450D01*
X471437Y680250D01*
Y679050D01*
X471637Y677850D01*
X472137Y676650D01*
X472737Y675850D01*
X473437Y675650D01*
X474137Y676050D01*
X474837Y677250D01*
G01X477737Y675650D02*
Y683650D01*
G01Y682050D02*
X478237Y682850D01*
X478737Y683450D01*
X479437Y683650D01*
X479937Y683450D01*
X480537Y682850D01*
G01X491137Y687650D02*
Y675650D01*
G01X488837Y687650D02*
X493437D01*
G01X497137Y675650D02*
X496337Y675850D01*
X495637Y676650D01*
X495037Y677850D01*
X494637Y679250D01*
X494437Y680850D01*
Y682450D01*
X494637Y684050D01*
X495037Y685450D01*
X495637Y686650D01*
X496337Y687450D01*
X497137Y687650D01*
X497937Y687450D01*
X498637Y686650D01*
X499237Y685450D01*
X499637Y684050D01*
X499837Y682450D01*
Y680850D01*
X499637Y679250D01*
X499237Y677850D01*
X498637Y676650D01*
X497937Y675850D01*
X497137Y675650D01*
G01X501137D02*
Y687650D01*
X503537D01*
X504337Y687050D01*
X504937Y685650D01*
X505137Y684050D01*
X504937Y682450D01*
X504437Y681250D01*
X503537Y680650D01*
X501137D01*
G01X26377Y-1D02*
Y46062D01*
G01D02*
G03X22440Y49999I-3937J0D01*
G01X102756Y290550D02*
G03Y298424I0J3937D01*
G01X133465D02*
G03Y290550I0J-3937D01*
G01X299606Y290551D02*
G03Y298425I0J3937D01*
G01X330314D02*
G03Y290551I0J-3937D01*
G01X353350Y224807D02*
X347051D01*
G02Y237406I0J6299D01*
G01X353350D01*
G02Y224807I0J-6299D01*
G01X496457Y290550D02*
G03Y298424I0J3937D01*
G01X527166D02*
G03Y290550I0J-3937D01*
G01X693308D02*
G03Y298424I0J3937D01*
G01X724016D02*
G03Y290550I0J-3937D01*
G01X800393Y588976D02*
Y542913D01*
G01D02*
G03X804330Y538976I3937J0D01*
G01X858267Y588976D02*
X800393D01*
G01X804330Y538976D02*
X830708D01*
G01X834645Y72440D02*
G03X826771I-3937J0D01*
G01Y103149D02*
G03X834645I3937J0D01*
G01Y210235D02*
G03X826771I-3937J0D01*
G01Y240944D02*
G03X834645I3937J0D01*
G01Y348031D02*
G03X826771I-3937J0D01*
G01Y378739D02*
G03X834645I3937J0D01*
G01Y485826D02*
G03X826771I-3937J0D01*
G01Y516535D02*
G03X834645I3937J-1D01*
G01Y535039D02*
G03X830708Y538976I-3937J0D01*
G01X834645Y72440D02*
Y-1D01*
G01D02*
X858267D01*
G01X853444Y15747D02*
G03I-6988J0D01*
G01X834645Y210235D02*
Y103149D01*
G01Y348031D02*
Y240944D01*
G01Y485826D02*
Y378739D01*
G01Y535039D02*
Y516535D01*
G01X853444Y573227D02*
G03I-6988J0D01*
G01X862204Y3936D02*
Y585039D01*
G01X858267Y-1D02*
G03X862204Y3936I0J3937D01*
G01Y585039D02*
G03X858267Y588976I-3937J0D01*
G54D13*
G01X517700Y23976D02*
X518769Y22907D01*
G01X517700Y35434D02*
Y23976D01*
G01X516500Y23923D02*
X515484Y22907D01*
G01X516500Y35480D02*
Y23923D01*
G01X518307Y36041D02*
X517700Y35434D01*
G01X518307Y38966D02*
Y36041D01*
G01X515945Y36035D02*
X516500Y35480D01*
G01X515945Y38966D02*
Y36035D01*
G01X518889Y250041D02*
Y261446D01*
G01X518307Y249459D02*
X518889Y250041D01*
G01X518307Y246430D02*
Y249459D01*
G01X520089Y250037D02*
Y261447D01*
G01X520670Y249456D02*
X520089Y250037D01*
G01X520670Y246430D02*
Y249456D01*
G01X518889Y261446D02*
X517846Y262489D01*
G01X520089Y261447D02*
X521131Y262489D01*
G01X535442Y10175D02*
Y21864D01*
G01X536023Y9594D02*
X535442Y10175D01*
G01X536023Y6630D02*
Y9594D01*
G01X534242Y10039D02*
Y21865D01*
G01X533661Y9458D02*
X534242Y10039D01*
G01X533661Y6630D02*
Y9458D01*
G01X535442Y21864D02*
X536485Y22907D01*
G01X534242Y21865D02*
X533200Y22907D01*
G01X536605Y263532D02*
X535562Y262489D01*
G01X536605Y275221D02*
Y263532D01*
G01X536024Y275802D02*
X536605Y275221D01*
G01X537805Y263531D02*
X538847Y262489D01*
G01X537805Y275357D02*
Y263531D01*
G01X536024Y278766D02*
Y275802D01*
G01X538386Y275938D02*
X537805Y275357D01*
G01X538386Y278766D02*
Y275938D01*
G01X556702Y10175D02*
Y21864D01*
G01X557283Y9594D02*
X556702Y10175D01*
G01X555502Y10039D02*
Y21865D01*
G01X554921Y9458D02*
X555502Y10039D01*
G01X554921Y6630D02*
Y9458D01*
G01X556702Y21864D02*
X557745Y22907D01*
G01X555502Y21865D02*
X554460Y22907D01*
G01X556684Y249936D02*
Y261446D01*
G01X556103Y249355D02*
X556684Y249936D01*
G01X556103Y246430D02*
Y249355D01*
G01X556684Y261446D02*
X555641Y262489D01*
G01X557283Y6630D02*
Y9594D01*
G01X557884Y249942D02*
Y261447D01*
G01X558465Y249361D02*
X557884Y249942D01*
G01X558465Y246430D02*
Y249361D01*
G01X557884Y261447D02*
X558926Y262489D01*
G01X576781Y23950D02*
X577824Y22907D01*
G01X576781Y35460D02*
Y23950D01*
G01X575581Y23949D02*
X574539Y22907D01*
G01X575581Y35454D02*
Y23949D01*
G01X577362Y36041D02*
X576781Y35460D01*
G01X577362Y38966D02*
Y36041D01*
G01X575000Y36035D02*
X575581Y35454D01*
G01X575000Y38966D02*
Y36035D01*
G01X574400Y263532D02*
X573357Y262489D01*
G01X574400Y275221D02*
Y263532D01*
G01X573819Y275802D02*
X574400Y275221D01*
G01X575600Y263531D02*
X576642Y262489D01*
G01X575600Y275357D02*
Y263531D01*
G01X573819Y278766D02*
Y275802D01*
G01X576181Y275938D02*
X575600Y275357D01*
G01X576181Y278766D02*
Y275938D01*
G01X602746Y10039D02*
Y21865D01*
G01X602165Y9458D02*
X602746Y10039D01*
G01X602165Y6630D02*
Y9458D01*
G01X602746Y21865D02*
X601704Y22907D01*
G01X603946Y10175D02*
Y21864D01*
G01X604527Y9594D02*
X603946Y10175D01*
G01X604527Y6630D02*
Y9594D01*
G01X603946Y21864D02*
X604989Y22907D01*
G01X649991Y263532D02*
X648948Y262489D01*
G01X649991Y275221D02*
Y263532D01*
G01X649410Y275802D02*
X649991Y275221D01*
G01X651191Y263531D02*
X652233Y262489D01*
G01X651191Y275357D02*
Y263531D01*
G01X649410Y278766D02*
Y275802D01*
G01X651772Y275938D02*
X651191Y275357D01*
G01X651772Y278766D02*
Y275938D01*
G01X679537Y10175D02*
Y21764D01*
G01X680118Y9594D02*
X679537Y10175D01*
G01X678337Y10039D02*
Y21765D01*
G01X677756Y9458D02*
X678337Y10039D01*
G01X677756Y6630D02*
Y9458D01*
G01X679537Y21764D02*
X680580Y22807D01*
G01X678337Y21765D02*
X677295Y22807D01*
G01X677156Y249936D02*
Y261446D01*
G01X676575Y249355D02*
X677156Y249936D01*
G01X676575Y246430D02*
Y249355D01*
G01X678356Y249942D02*
Y261447D01*
G01X678937Y249361D02*
X678356Y249942D01*
G01X678937Y246430D02*
Y249361D01*
G01X677156Y261446D02*
X676113Y262489D01*
G01X678356Y261447D02*
X679398Y262489D01*
G01X680118Y6630D02*
Y9594D01*
G01X695057Y22853D02*
X695029D01*
G01X696053Y23849D02*
X695057Y22853D01*
G01X695472Y36035D02*
X696053Y35454D01*
G01X695472Y38966D02*
Y36035D01*
G01X698248Y22855D02*
X698277D01*
G01X697253Y23850D02*
X698248Y22855D01*
G01X697253Y35460D02*
Y23850D01*
G01X696053Y35454D02*
Y23849D01*
G01X697834Y36041D02*
X697253Y35460D01*
G01X697834Y38966D02*
Y36041D01*
G01X697235Y263532D02*
X696192Y262489D01*
G01X697235Y275221D02*
Y263532D01*
G01X696654Y275802D02*
X697235Y275221D01*
G01X698435Y263531D02*
X699477Y262489D01*
G01X698435Y275357D02*
Y263531D01*
G01X696654Y278766D02*
Y275802D01*
G01X699016Y275938D02*
X698435Y275357D01*
G01X699016Y278766D02*
Y275938D01*
G01X717332Y10175D02*
Y15773D01*
G01X717913Y9594D02*
X717332Y10175D01*
G01X717913Y6630D02*
Y9594D01*
G01X716132Y10039D02*
Y15275D01*
G01X715551Y9458D02*
X716132Y10039D01*
G01X715551Y6630D02*
Y9458D01*
G01X717332Y21864D02*
X718375Y22907D01*
G01X717332Y19009D02*
Y21864D01*
G01X716700Y18377D02*
X717332Y19009D01*
G01X716700Y16405D02*
Y18377D01*
G01X717332Y15773D02*
X716700Y16405D01*
G01X716132Y21865D02*
X715090Y22907D01*
G01X716132Y19507D02*
Y21865D01*
G01X715500Y18875D02*
X716132Y19507D01*
G01X715500Y15907D02*
Y18875D01*
G01X716132Y15275D02*
X715500Y15907D01*
G01X718495Y263532D02*
X717452Y262489D01*
G01X718495Y275221D02*
Y263532D01*
G01X717914Y275802D02*
X718495Y275221D01*
G01X719695Y263531D02*
X720737Y262489D01*
G01X719695Y275357D02*
Y263531D01*
G01X717914Y278766D02*
Y275802D01*
G01X720276Y275938D02*
X719695Y275357D01*
G01X720276Y278766D02*
Y275938D01*
G01X735600Y23607D02*
X736091D01*
G01X734748Y24459D02*
X735600Y23607D01*
G01X734748Y26755D02*
Y24459D01*
G01X737000Y29007D02*
X734748Y26755D01*
G01X733548Y24349D02*
X732806Y23607D01*
G01X733548Y27253D02*
Y24349D01*
G01X735800Y29505D02*
X733548Y27253D01*
G01X737000Y31907D02*
Y29007D01*
G01X736374Y32533D02*
X737000Y31907D01*
G01X736374Y34652D02*
Y32533D01*
G01X735630Y35396D02*
X736374Y34652D01*
G01X735630Y38966D02*
Y35396D01*
G01X735800Y31409D02*
Y29505D01*
G01X735174Y32035D02*
X735800Y31409D01*
G01X735174Y34140D02*
Y32035D01*
G01X733267Y36047D02*
X735174Y34140D01*
G01X733267Y38966D02*
Y36047D01*
G01X735800Y256500D02*
Y261857D01*
G01X736637Y255663D02*
X735800Y256500D01*
G01X736637Y250362D02*
Y255663D01*
G01X735630Y249355D02*
X736637Y250362D01*
G01X735630Y246430D02*
Y249355D01*
G01X737000Y256998D02*
Y261036D01*
G01X737837Y256161D02*
X737000Y256998D01*
G01X737837Y249516D02*
Y256161D01*
G01X737992Y249361D02*
X737837Y249516D01*
G01X737992Y246430D02*
Y249361D01*
G01X735800Y261857D02*
X735168Y262489D01*
G01X737000Y261036D02*
X738453Y262489D01*
G54D14*
G01X14300Y232339D02*
X13090Y231129D01*
G01X16761Y232339D02*
X14300D01*
G01X29025Y220075D02*
X16761Y232339D01*
G01X14300Y233689D02*
X13090Y234899D01*
G01X17321Y233689D02*
X14300D01*
G01X29585Y221425D02*
X17321Y233689D01*
G01X14800Y244150D02*
X13590Y242940D01*
G01X17777Y244150D02*
X14800D01*
G01X8810Y238301D02*
X7600Y237091D01*
G01X16699Y238301D02*
X8810D01*
G01X27925Y227075D02*
X16699Y238301D01*
G01X8810Y239651D02*
X7600Y240861D01*
G01X17259Y239651D02*
X8810D01*
G01X28485Y228425D02*
X17259Y239651D01*
G01X14800Y245500D02*
X13590Y246710D01*
G01X18337Y245500D02*
X14800D01*
G01Y257311D02*
X13590Y258521D01*
G01X18775Y257311D02*
X14800D01*
G01Y255961D02*
X13590Y254751D01*
G01X18215Y255961D02*
X14800D01*
G01X8810Y250112D02*
X7600Y248902D01*
G01X18164Y250112D02*
X8810D01*
G01Y251462D02*
X7600Y252672D01*
G01X18724Y251462D02*
X8810D01*
G01Y261923D02*
X7600Y260713D01*
G01X18067Y261923D02*
X8810D01*
G01Y263273D02*
X7600Y264483D01*
G01X18627Y263273D02*
X8810D01*
G01X33275Y200575D02*
X32000Y199300D01*
G01X33275Y201925D02*
X32000Y203200D01*
G01X30625Y220075D02*
X29025D01*
G01X31700Y219000D02*
X30625Y220075D01*
G01Y221425D02*
X29585D01*
G01X31700Y222500D02*
X30625Y221425D01*
G01Y227075D02*
X27925D01*
G01X31700Y226000D02*
X30625Y227075D01*
G01Y228425D02*
X28485D01*
G01X31700Y229500D02*
X30625Y228425D01*
G01X27752Y234175D02*
X17777Y244150D01*
G01X30525Y234175D02*
X27752D01*
G01X31700Y233000D02*
X30525Y234175D01*
G01X28312Y235525D02*
X18337Y245500D01*
G01X30725Y235525D02*
X28312D01*
G01X31700Y236500D02*
X30725Y235525D01*
G01X27201Y241075D02*
X18164Y250112D01*
G01X30625Y241075D02*
X27201D01*
G01X31700Y240000D02*
X30625Y241075D01*
G01X27761Y242425D02*
X18724Y251462D01*
G01X30625Y242425D02*
X27761D01*
G01X31700Y243500D02*
X30625Y242425D01*
G01X26561Y249525D02*
X18775Y257311D01*
G01X30725Y249525D02*
X26561D01*
G01X31700Y250500D02*
X30725Y249525D01*
G01X26001Y248175D02*
X18215Y255961D01*
G01X30525Y248175D02*
X26001D01*
G01X31700Y247000D02*
X30525Y248175D01*
G01X24915Y255075D02*
X18067Y261923D01*
G01X30625Y255075D02*
X24915D01*
G01X31700Y254000D02*
X30625Y255075D01*
G01X25475Y256425D02*
X18627Y263273D01*
G01X30625Y256425D02*
X25475D01*
G01X31700Y257500D02*
X30625Y256425D01*
G01X47950Y190240D02*
X49340Y188850D01*
G01X47950Y194850D02*
Y190240D01*
G01X49506Y196406D02*
X47950Y194850D01*
G01X47400Y200675D02*
X48325D01*
G01X46800Y200075D02*
X47400Y200675D01*
G01X46800Y198800D02*
Y200075D01*
G01X47375Y202025D02*
X48885D01*
G01X46800Y202600D02*
X47375Y202025D01*
G01X46800Y203700D02*
Y202600D01*
G01X40200Y198800D02*
X37600D01*
G01X40200Y203700D02*
X37600D01*
G01X43000Y212700D02*
X40400D01*
G01X43000Y207800D02*
X40400D01*
G01X42025Y200575D02*
X33275D01*
G01X43200Y199400D02*
X42025Y200575D01*
G01X43200Y198800D02*
Y199400D01*
G01X42225Y201925D02*
X33275D01*
G01X43200Y202900D02*
X42225Y201925D01*
G01X43200Y203700D02*
Y202900D01*
G01X36075Y209575D02*
X34800Y208300D01*
G01X44825Y209575D02*
X36075D01*
G01X46000Y208400D02*
X44825Y209575D01*
G01X46000Y207800D02*
Y208400D01*
G01X36075Y210925D02*
X34800Y212200D01*
G01X45025Y210925D02*
X36075D01*
G01X46000Y211900D02*
X45025Y210925D01*
G01X46000Y212700D02*
Y211900D01*
G01X35300Y219000D02*
X37900D01*
G01X35300Y222500D02*
X37900D01*
G01Y226000D02*
X35300D01*
G01X37900Y233000D02*
X35300D01*
G01X38000Y236500D02*
X35300D01*
G01X37900Y229500D02*
X35300D01*
G01X37900Y240000D02*
X35300D01*
G01X37900Y243500D02*
X35300D01*
G01X38000Y250500D02*
X35300D01*
G01X37900Y247000D02*
X35300D01*
G01X37900Y254000D02*
X35300D01*
G01X37900Y257500D02*
X35300D01*
G01X50650Y188850D02*
X51860Y187640D01*
G01X49340Y188850D02*
X50650D01*
G01X49506Y199494D02*
Y196406D01*
G01X50650Y190200D02*
X51860Y191410D01*
G01X49900Y190200D02*
X50650D01*
G01X49300Y190800D02*
X49900Y190200D01*
G01X49300Y194290D02*
Y190800D01*
G01X50856Y195846D02*
X49300Y194290D01*
G01X50856Y200054D02*
Y195846D01*
G01X57050Y185710D02*
X55720Y184380D01*
G01X57050Y192502D02*
Y185710D01*
G01X54650Y194902D02*
X57050Y192502D01*
G01X54650Y197590D02*
Y194902D01*
G01X53860Y198380D02*
X54650Y197590D01*
G01X58400Y185359D02*
X59379Y184380D01*
G01X58400Y193062D02*
Y185359D01*
G01X56000Y195462D02*
X58400Y193062D01*
G01X56000Y207910D02*
Y195462D01*
G01X48325Y200675D02*
X49506Y199494D01*
G01X48885Y202025D02*
X50856Y200054D01*
G01X53860Y200030D02*
Y198380D01*
G01X54650Y200820D02*
X53860Y200030D01*
G01X54650Y202470D02*
Y200820D01*
G01X53860Y203260D02*
X54650Y202470D01*
G01X53860Y204910D02*
Y203260D01*
G01X54650Y205700D02*
X53860Y204910D01*
G01X54650Y207350D02*
Y205700D01*
G01X52000Y210000D02*
X54650Y207350D01*
G01X50400Y210000D02*
X52000D01*
G01X49600Y209200D02*
X50400Y210000D01*
G01X49600Y207800D02*
Y209200D01*
G01X52560Y211350D02*
X56000Y207910D01*
G01X50315Y211350D02*
X52560D01*
G01X49600Y212065D02*
X50315Y211350D01*
G01X49600Y212700D02*
Y212065D01*
G01X76181Y24392D02*
Y31407D01*
G01X78824Y39150D02*
X80031Y40357D01*
G01X78824Y32676D02*
Y39150D01*
G01X80118Y31382D02*
X78824Y32676D01*
G01X77474Y39294D02*
X76411Y40357D01*
G01X77474Y32700D02*
Y39294D01*
G01X76181Y31407D02*
X77474Y32700D01*
G01X80118Y24392D02*
Y31382D01*
G01X91929Y24392D02*
Y31606D01*
G01X93223Y39293D02*
X92159Y40357D01*
G01X93223Y32900D02*
Y39293D01*
G01X91929Y31606D02*
X93223Y32900D01*
G01X107677Y24392D02*
Y31507D01*
G01X95866Y24392D02*
Y31534D01*
G01X108970Y39294D02*
X107907Y40357D01*
G01X108970Y32800D02*
Y39294D01*
G01X107677Y31507D02*
X108970Y32800D01*
G01X94573Y39151D02*
X95779Y40357D01*
G01X94573Y32827D02*
Y39151D01*
G01X95866Y31534D02*
X94573Y32827D01*
G01X111614Y24392D02*
Y31406D01*
G01X123425Y24392D02*
Y31406D01*
G01X110320Y39150D02*
X111527Y40357D01*
G01X110320Y32700D02*
Y39150D01*
G01X111614Y31406D02*
X110320Y32700D01*
G01X124719Y39293D02*
X123655Y40357D01*
G01X124719Y32700D02*
Y39293D01*
G01X123425Y31406D02*
X124719Y32700D01*
G01X111200Y75026D02*
Y67200D01*
G01X111162Y75064D02*
X111200Y75026D01*
G01X111162Y78244D02*
Y75064D01*
G01X112101Y79183D02*
X111162Y78244D01*
G01X115917Y79183D02*
X112101D01*
G01X120125Y83391D02*
X115917Y79183D01*
G01X120125Y89308D02*
Y83391D01*
G01X132025Y101208D02*
X120125Y89308D01*
G01X139173Y24392D02*
Y33256D01*
G01X127362Y24392D02*
Y31507D01*
G01X140467Y39293D02*
X139403Y40357D01*
G01X140467Y34550D02*
Y39293D01*
G01X139173Y33256D02*
X140467Y34550D01*
G01X126069Y39151D02*
X127275Y40357D01*
G01X126069Y32800D02*
Y39151D01*
G01X127362Y31507D02*
X126069Y32800D01*
G01X132025Y112161D02*
Y101208D01*
G01X138189Y118325D02*
X132025Y112161D01*
G01X143220Y118325D02*
X138189D01*
G01X143110Y24392D02*
Y33257D01*
G01X154921Y24392D02*
Y33257D01*
G01X141817Y39151D02*
X143023Y40357D01*
G01X141817Y34550D02*
Y39151D01*
G01X143110Y33257D02*
X141817Y34550D01*
G01X156214Y39294D02*
X155151Y40357D01*
G01X154921Y33257D02*
X156214Y34550D01*
G01X147310Y116360D02*
X143220D01*
G01X147550Y116600D02*
X147310Y116360D01*
G01X149570Y116600D02*
X147550D01*
G01X150670Y115500D02*
X149570Y116600D01*
G01X149720Y117950D02*
X150670Y118900D01*
G01X147400Y117950D02*
X149720D01*
G01X147025Y118325D02*
X147400Y117950D01*
G01X143220Y118325D02*
X147025D01*
G01X158858Y24392D02*
Y33256D01*
G01X170669Y24392D02*
Y33256D01*
G01X157564Y39150D02*
X158771Y40357D01*
G01X157564Y34550D02*
Y39150D01*
G01X158858Y33256D02*
X157564Y34550D01*
G01X156214D02*
Y39294D01*
G01X171963Y39293D02*
X170899Y40357D01*
G01X170669Y33256D02*
X171963Y34550D01*
G01X174606Y24392D02*
Y33257D01*
G01X186417Y24392D02*
Y33256D01*
G01X173313Y39151D02*
X174519Y40357D01*
G01X173313Y34550D02*
Y39151D01*
G01X174606Y33257D02*
X173313Y34550D01*
G01X171963D02*
Y39293D01*
G01X187711D02*
X186647Y40357D01*
G01X186417Y33256D02*
X187711Y34550D01*
G01X190354Y24392D02*
Y33257D01*
G01X202165Y24392D02*
Y33257D01*
G01X195525Y41475D02*
X194445Y40395D01*
G01X195525Y47375D02*
Y41475D01*
G01X196875Y41593D02*
X198073Y40395D01*
G01X196875Y47375D02*
Y41593D01*
G01X189061Y39151D02*
X190267Y40357D01*
G01X189061Y34550D02*
Y39151D01*
G01X190354Y33257D02*
X189061Y34550D01*
G01X187711D02*
Y39293D01*
G01X202165Y33257D02*
X203458Y34550D01*
G01X194700Y48200D02*
X195525Y47375D01*
G01X194700Y51800D02*
Y54400D01*
G01X197700Y51800D02*
Y54400D01*
G01Y48200D02*
X196875Y47375D01*
G01X206102Y24392D02*
Y33256D01*
G01X207775Y43275D02*
Y47875D01*
G01X204808Y40308D02*
X207775Y43275D01*
G01X204808Y34550D02*
Y40308D01*
G01X206102Y33256D02*
X204808Y34550D01*
G01X206425Y43835D02*
Y47875D01*
G01X203458Y40868D02*
X206425Y43835D01*
G01X203458Y34550D02*
Y40868D01*
G01X207775Y47875D02*
X208600Y48700D01*
G01X206425Y47875D02*
X205600Y48700D01*
G01X208600Y54800D02*
X208700Y54900D01*
G01X208600Y52300D02*
Y54800D01*
G01X205600Y54600D02*
X205300Y54900D01*
G01X205600Y52300D02*
Y54600D01*
G01X233655Y41993D02*
X232591Y43057D01*
G01X237598Y24392D02*
Y33257D01*
G01X233661Y24392D02*
Y33256D01*
G01X235005Y41851D02*
X236211Y43057D01*
G01X235005Y40095D02*
Y41851D01*
G01X236305Y38795D02*
X235005Y40095D01*
G01X236305Y34550D02*
Y38795D01*
G01X237598Y33257D02*
X236305Y34550D01*
G01X233655Y39535D02*
Y41993D01*
G01X234955Y38235D02*
X233655Y39535D01*
G01X234955Y34550D02*
Y38235D01*
G01X233661Y33256D02*
X234955Y34550D01*
G01X253346Y24392D02*
Y33256D01*
G01X249409Y24392D02*
Y33257D01*
G01X252052Y34550D02*
Y44152D01*
G01X253346Y33256D02*
X252052Y34550D01*
G01X250702D02*
Y44712D01*
G01X249409Y33257D02*
X250702Y34550D01*
G01X252675Y50875D02*
X253500Y51700D01*
G01X252675Y44775D02*
Y50875D01*
G01X252052Y44152D02*
X252675Y44775D01*
G01X251325Y50875D02*
X250500Y51700D01*
G01X251325Y45335D02*
Y50875D01*
G01X250702Y44712D02*
X251325Y45335D01*
G01X253500Y55300D02*
Y57900D01*
G01X250500Y55300D02*
Y57900D01*
G01X269094Y24392D02*
Y33256D01*
G01X265157Y24392D02*
Y33257D01*
G01X267700Y39280D02*
X268910Y40490D01*
G01X267700Y34650D02*
Y39280D01*
G01X269094Y33256D02*
X267700Y34650D01*
G01X266350Y39280D02*
X265140Y40490D01*
G01X266350Y34450D02*
Y39280D01*
G01X265157Y33257D02*
X266350Y34450D01*
G01X274900Y103540D02*
Y108900D01*
G01X276290Y102150D02*
X274900Y103540D01*
G01X279610Y102150D02*
X276290D01*
G01X276250Y104100D02*
Y109460D01*
G01X276850Y103500D02*
X276250Y104100D01*
G01X279050Y103500D02*
X276850D01*
G01X279650Y104100D02*
X279050Y103500D01*
G01X273348Y109500D02*
X272200Y108352D01*
G01X274300Y109500D02*
X273348D01*
G01X274900Y108900D02*
X274300Y109500D01*
G01X273166Y110850D02*
X272185Y111831D01*
G01X274860Y110850D02*
X273166D01*
G01X276250Y109460D02*
X274860Y110850D01*
G01X284842Y24392D02*
Y33256D01*
G01X280905Y24392D02*
Y33257D01*
G01X283548Y39280D02*
X284758Y40490D01*
G01X283548Y34550D02*
Y39280D01*
G01X284842Y33256D02*
X283548Y34550D01*
G01X282198Y39280D02*
X280988Y40490D01*
G01X282198Y34550D02*
Y39280D01*
G01X280905Y33257D02*
X282198Y34550D01*
G01X281000Y103540D02*
X279610Y102150D01*
G01X281000Y105420D02*
Y103540D01*
G01X281790Y106210D02*
X281000Y105420D01*
G01X279650Y110860D02*
Y104100D01*
G01X281790Y107860D02*
Y106210D01*
G01X281000Y108650D02*
X281790Y107860D01*
G01X281000Y110300D02*
Y108650D01*
G01X281855Y111155D02*
X281000Y110300D01*
G01X284195Y111155D02*
X281855D01*
G01X284985Y110365D02*
X284195Y111155D01*
G01X286635Y110365D02*
X284985D01*
G01X287425Y111155D02*
X286635Y110365D01*
G01X289075Y111155D02*
X287425D01*
G01X289865Y110365D02*
X289075Y111155D01*
G01X291515Y110365D02*
X289865D01*
G01X292305Y111155D02*
X291515Y110365D01*
G01X293955Y111155D02*
X292305D01*
G01X295905Y113105D02*
X293955Y111155D01*
G01X281295Y112505D02*
X279650Y110860D01*
G01X293395Y112505D02*
X281295D01*
G01X294555Y113665D02*
X293395Y112505D01*
G01X294555Y116155D02*
Y113665D01*
G01X307105Y128705D02*
X294555Y116155D01*
G01X300590Y24392D02*
Y33256D01*
G01X296653Y24392D02*
Y33257D01*
G01X299296Y39280D02*
X300506Y40490D01*
G01X299296Y34550D02*
Y39280D01*
G01X300590Y33256D02*
X299296Y34550D01*
G01X297946Y39280D02*
X296736Y40490D01*
G01X297946Y34550D02*
Y39280D01*
G01X296653Y33257D02*
X297946Y34550D01*
G01X295905Y115595D02*
Y113105D01*
G01X297313Y117003D02*
X295905Y115595D01*
G01X298431Y117003D02*
X297313D01*
G01X299597Y118170D02*
X298431Y117003D01*
G01X299597Y119287D02*
Y118170D01*
G01X300764Y120454D02*
X299597Y119287D01*
G01X301881Y120454D02*
X300764D01*
G01X303048Y121620D02*
X301881Y120454D01*
G01X307500Y122831D02*
X314058Y129389D01*
G01X307500Y122700D02*
Y122831D01*
G01X309700Y123120D02*
Y122796D01*
G01X313290Y126710D02*
X309700Y123120D01*
G01X303048Y122738D02*
Y121620D01*
G01X304214Y123904D02*
X303048Y122738D01*
G01X305332Y123904D02*
X304214D01*
G01X306498Y125071D02*
X305332Y123904D01*
G01X306498Y126188D02*
Y125071D01*
G01X307665Y127355D02*
X306498Y126188D01*
G01X309255Y127355D02*
X307665D01*
G01X312431Y130531D02*
X309255Y127355D01*
G01X308695Y128705D02*
X307105D01*
G01X311871Y131881D02*
X308695Y128705D01*
G01X316338Y24392D02*
Y33256D01*
G01X312401Y24392D02*
Y33257D01*
G01X315044Y39480D02*
X316254Y40690D01*
G01X315044Y34550D02*
Y39480D01*
G01X316338Y33256D02*
X315044Y34550D01*
G01X313694Y39480D02*
X312484Y40690D01*
G01X313694Y34550D02*
Y39480D01*
G01X312401Y33257D02*
X313694Y34550D01*
G01X317869Y129131D02*
X318702D01*
G01X316499Y130501D02*
X317869Y129131D01*
G01X315222Y130501D02*
X316499D01*
G01X314110Y129389D02*
X315222Y130501D01*
G01X314058Y129389D02*
X314110D01*
G01X314618Y128039D02*
X313290Y126710D01*
G01X314670Y128039D02*
X314618D01*
G01X315782Y129151D02*
X314670Y128039D01*
G01X313392Y130531D02*
X312431D01*
G01X313952Y131881D02*
X311871D01*
G01X314292Y131541D02*
X313952Y131881D01*
G01X317332Y131541D02*
X314292D01*
G01X319454Y123261D02*
X319418Y123225D01*
G01X321922Y123261D02*
X319454D01*
G01X316070Y122600D02*
X315451Y123219D01*
G01X316731Y122600D02*
X316070D01*
G01X317352Y123221D02*
X316731Y122600D01*
G01X324587Y196696D02*
X323331D01*
G01X325782Y197891D02*
X324587Y196696D01*
G01X319801Y195260D02*
Y194890D01*
G01X321442Y196901D02*
X319801Y195260D01*
G01X316860Y196026D02*
X316844Y196010D01*
G01X316860Y196410D02*
Y196026D01*
G01X320001Y199551D02*
X316860Y196410D01*
G01X323018Y198618D02*
X322256D01*
G01X323772Y199372D02*
X323018Y198618D01*
G01X323772Y199771D02*
Y199372D01*
G01X326442Y201525D02*
X325642Y202325D01*
G01X320332Y199551D02*
X320001D01*
G01X316850Y238550D02*
X316000Y237700D01*
G01X316850Y240760D02*
Y238550D01*
G01X318740Y242650D02*
X316850Y240760D01*
G01X325906Y242650D02*
X318740D01*
G01X318200Y238600D02*
X319100Y237700D01*
G01X318200Y240200D02*
Y238600D01*
G01X319300Y241300D02*
X318200Y240200D01*
G01X326466Y241300D02*
X319300D01*
G01X332086Y24392D02*
Y33256D01*
G01X328149Y24392D02*
Y33257D01*
G01X330792Y39856D02*
X331931Y40995D01*
G01X330792Y34550D02*
Y39856D01*
G01X332086Y33256D02*
X330792Y34550D01*
G01X329442Y39856D02*
X328303Y40995D01*
G01X329442Y34550D02*
Y39856D01*
G01X328149Y33257D02*
X329442Y34550D01*
G01X340140Y96950D02*
X346940D01*
G01X338490Y95300D02*
X340140Y96950D01*
G01X337154Y95300D02*
X338490D01*
G01X336750Y95704D02*
X337154Y95300D01*
G01X340700Y95600D02*
X347500D01*
G01X338950Y93850D02*
X340700Y95600D01*
G01X337100Y93850D02*
X338950D01*
G01X336750Y93500D02*
X337100Y93850D01*
G01X332445Y104561D02*
X333313Y103693D01*
G01X331622Y104561D02*
X332445D01*
G01X338560Y99050D02*
X342938D01*
G01X338010Y98500D02*
X338560Y99050D01*
G01X330600Y98500D02*
X338010D01*
G01X330100Y98000D02*
X330600Y98500D01*
G01X338000Y100400D02*
X342378D01*
G01X337450Y99850D02*
X338000Y100400D01*
G01X330450Y99850D02*
X337450D01*
G01X330100Y100200D02*
X330450Y99850D01*
G01X333595Y118101D02*
X333534Y118040D01*
G01X337352Y118101D02*
X333595D01*
G01X334202Y121101D02*
X333601Y120500D01*
G01X332621Y107481D02*
X333434Y106668D01*
G01X331652Y107481D02*
X332621D01*
G01X329100Y119923D02*
X329415D01*
G01X327822Y121201D02*
X329100Y119923D01*
G01X337352Y121101D02*
X334202D01*
G01X329637Y122386D02*
X329308D01*
G01X330822Y121201D02*
X329637Y122386D01*
G01X335400Y196369D02*
Y196300D01*
G01X336722Y197691D02*
X335400Y196369D01*
G01X337818Y189200D02*
X337800D01*
G01X339172Y190554D02*
X337818Y189200D01*
G01X339172Y190561D02*
Y190554D01*
G01X337818Y192200D02*
X337800D01*
G01X339172Y193554D02*
X337818Y192200D01*
G01X339172Y193561D02*
Y193554D01*
G01X336412Y187678D02*
X334707Y189383D01*
G01X336412Y187561D02*
Y187678D01*
G01X334910Y192063D02*
X333996D01*
G01X336412Y190561D02*
X334910Y192063D01*
G01X329972Y193441D02*
Y193559D01*
G01X331352Y192061D02*
X329972Y193441D01*
G01Y196341D02*
Y196400D01*
G01X331252Y195061D02*
X329972Y196341D01*
G01X331352Y195061D02*
X331252D01*
G01X327011Y192061D02*
X328592D01*
G01X326550Y191600D02*
X327011Y192061D01*
G01X327431Y193900D02*
X328592Y195061D01*
G01X326850Y193900D02*
X327431D01*
G01X328089Y202531D02*
X328532D01*
G01X327216Y203404D02*
X328089Y202531D01*
G01X327216Y203902D02*
Y203404D01*
G01X326442Y200601D02*
Y201525D01*
G01X336842Y200420D02*
X335739Y199317D01*
G01X336842Y202551D02*
Y200420D01*
G01X328510Y219010D02*
Y218320D01*
G01X336150Y226650D02*
X328510Y219010D01*
G01X336150Y239950D02*
Y226650D01*
G01X327614Y220024D02*
X327024D01*
G01X330233Y222643D02*
X327614Y220024D01*
G01X330233Y223433D02*
Y222643D01*
G01X331400Y224600D02*
X330233Y223433D01*
G01X332190Y224600D02*
X331400D01*
G01X334800Y227210D02*
X332190Y224600D01*
G01X334800Y240510D02*
Y227210D01*
G01X342927Y246727D02*
X336150Y239950D01*
G01X342367Y248077D02*
X334800Y240510D01*
G01X332050Y241367D02*
X341310Y250627D01*
G01X332050Y235950D02*
Y241367D01*
G01X331142Y235042D02*
X332050Y235950D01*
G01X331142Y233658D02*
Y235042D01*
G01X330700Y241927D02*
X340750Y251977D01*
G01X330700Y236510D02*
Y241927D01*
G01X330036Y235846D02*
X330700Y236510D01*
G01X328945Y235846D02*
X330036D01*
G01X339133Y255877D02*
X325906Y242650D01*
G01X339693Y254527D02*
X326466Y241300D01*
G01X340750Y251977D02*
X371033D01*
G01X372650Y255877D02*
X339133D01*
G01X372090Y254527D02*
X339693D01*
G01X349352Y99362D02*
Y104561D01*
G01X346940Y96950D02*
X349352Y99362D01*
G01X350702Y105121D02*
X349382Y106441D01*
G01X350702Y98802D02*
Y105121D01*
G01X347500Y95600D02*
X350702Y98802D01*
G01X345302Y101414D02*
Y103911D01*
G01X342938Y99050D02*
X345302Y101414D01*
G01X343952Y104471D02*
X344992Y105511D01*
G01X343952Y101974D02*
Y104471D01*
G01X342378Y100400D02*
X343952Y101974D01*
G01X349382Y106441D02*
Y107481D01*
G01X347932Y116499D02*
X346596Y115163D01*
G01X347932Y116601D02*
Y116499D01*
G01Y119499D02*
X346596Y118163D01*
G01X347932Y119601D02*
Y119499D01*
G01X344992Y105511D02*
Y108061D01*
G01X354734Y181561D02*
X353302Y182993D01*
G01X354812Y181561D02*
X354734D01*
G01X344232Y181151D02*
X342363Y183020D01*
G01X344232Y180061D02*
Y181151D01*
G01X343269Y190024D02*
X342342D01*
G01X344232Y189061D02*
X343269Y190024D01*
G01X342350Y192225D02*
X342339D01*
G01X342350Y192224D02*
Y192225D01*
G01X342513Y192061D02*
X342350Y192224D01*
G01X344232Y192061D02*
X342513D01*
G01X349913Y189700D02*
X349100D01*
G01X352052Y187561D02*
X349913Y189700D01*
G01X350796Y191817D02*
X352052Y190561D01*
G01X349183Y191817D02*
X350796D01*
G01X349100Y191900D02*
X349183Y191817D01*
G01X345500Y190504D02*
Y190500D01*
G01X346992Y191996D02*
X345500Y190504D01*
G01X346992Y192061D02*
Y191996D01*
G01X345596Y193567D02*
X345503Y193474D01*
G01X345596Y193665D02*
Y193567D01*
G01X346992Y195061D02*
X345596Y193665D01*
G01X353625Y191748D02*
Y192045D01*
G01X354812Y190561D02*
X353625Y191748D01*
G01Y194748D02*
Y195045D01*
G01X354812Y193561D02*
X353625Y194748D01*
G01X354812Y184654D02*
X353342Y186124D01*
G01X354812Y184561D02*
Y184654D01*
G01X343713Y184159D02*
X342233Y185639D01*
G01X343713Y183580D02*
Y184159D01*
G01X344232Y183061D02*
X343713Y183580D01*
G01X342363Y183186D02*
X342188Y183361D01*
G01X342363Y183020D02*
Y183186D01*
G01X346939Y183061D02*
X345500Y184500D01*
G01X346992Y183061D02*
X346939D01*
G01X346990Y186061D02*
X345631Y187420D01*
G01X346992Y186061D02*
X346990D01*
G01X358756Y246727D02*
X342927D01*
G01X359316Y248077D02*
X342367D01*
G01X341310Y250627D02*
X370473D01*
G01X370100Y119809D02*
Y119563D01*
G01X371392Y121101D02*
X370100Y119809D01*
G01X371392Y118101D02*
X372700Y119409D01*
G01X365275Y190561D02*
X364895Y190941D01*
G01X367692Y190561D02*
X365275D01*
G01X367652Y193601D02*
X367692Y193561D01*
G01X365407Y193601D02*
X367652D01*
G01X364947Y193141D02*
X365407Y193601D01*
G01X369200Y188812D02*
Y189100D01*
G01X370452Y187561D02*
X369200Y188812D01*
G01X369110Y191903D02*
X369106D01*
G01X370452Y190561D02*
X369110Y191903D01*
G01X362632Y189325D02*
X361257Y190700D01*
G01X362632Y189061D02*
Y189325D01*
G01Y192149D02*
Y192061D01*
G01X361257Y193524D02*
X362632Y192149D01*
G01X358633Y193300D02*
X356700D01*
G01X359872Y192061D02*
X358633Y193300D01*
G01X357239Y195061D02*
X356600Y195700D01*
G01X359872Y195061D02*
X357239D01*
G01X364300Y241183D02*
X358756Y246727D01*
G01X364300Y229390D02*
Y241183D01*
G01X365650Y241743D02*
X359316Y248077D01*
G01X365650Y229390D02*
Y241743D01*
G01X370473Y250627D02*
X376525Y244575D01*
G01X371033Y251977D02*
X377875Y245135D01*
G01X372700Y119409D02*
Y119663D01*
G01X374223Y190350D02*
X374000D01*
G01X375512Y189061D02*
X374223Y190350D01*
G01X374470Y193103D02*
X373922D01*
G01X375512Y192061D02*
X374470Y193103D01*
G01X376196Y226576D02*
X381850Y232230D01*
G01X375241Y227531D02*
X380500Y232790D01*
G01X376525Y244575D02*
Y234075D01*
G01X377875Y245135D02*
Y234075D01*
G01X381850Y232230D02*
Y246677D01*
G01X380500Y232790D02*
Y246117D01*
G01X381850Y246677D02*
X372650Y255877D01*
G01X380500Y246117D02*
X372090Y254527D01*
G01X394229Y239721D02*
Y241128D01*
G01X401100Y232850D02*
X394229Y239721D01*
G01X408350Y232850D02*
X401100D01*
G01X393280Y238760D02*
X391788D01*
G01X397361Y234679D02*
X393280Y238760D01*
G01X397361Y233562D02*
Y234679D01*
G01X398528Y232395D02*
X397361Y233562D01*
G01X399645Y232395D02*
X398528D01*
G01X400540Y231500D02*
X399645Y232395D01*
G01X408350Y231500D02*
X400540D01*
G01X415552Y118239D02*
X416904Y119591D01*
G01X415552Y118101D02*
Y118239D01*
G01X416851Y122400D02*
Y122600D01*
G01X415552Y121101D02*
X416851Y122400D01*
G54D15*
G01X606750Y255550D02*
X606700Y255600D01*
G01X606750Y252334D02*
Y255550D01*
G01X608071Y251013D02*
X606750Y252334D01*
G01X608071Y246430D02*
Y251013D01*
G01X605300Y253168D02*
X604074Y254394D01*
G01X605300Y251733D02*
Y253168D01*
G01X605709Y251324D02*
X605300Y251733D01*
G01X605709Y246430D02*
Y251324D01*
G01X609216Y272889D02*
X609896D01*
G01X608640Y273465D02*
X609216Y272889D01*
G01X608640Y275086D02*
Y273465D01*
G01X609252Y275698D02*
X608640Y275086D01*
G01X607190Y272012D02*
X608996Y270206D01*
G01X607190Y275000D02*
Y272012D01*
G01X606890Y275300D02*
X607190Y275000D01*
G01X609252Y278766D02*
Y275698D01*
G01X606890Y278766D02*
Y275300D01*
G01X644685Y12415D02*
X644193Y12907D01*
G01X644685Y6630D02*
Y12415D01*
G01X646135Y10742D02*
Y14672D01*
G01X647047Y9830D02*
X646135Y10742D01*
G01X647047Y6630D02*
Y9830D01*
G01X646135Y14672D02*
X645300Y15507D01*
G01X646778Y29829D02*
X647000Y29607D01*
G01X646778Y35245D02*
Y29829D01*
G01X645866Y36157D02*
X646778Y35245D01*
G01X645866Y38966D02*
Y36157D01*
G01X648228Y32254D02*
X649550Y30932D01*
G01X648228Y38966D02*
Y32254D01*
G01X649550Y30932D02*
Y30807D01*
M02*
